# T6G (Grand Teton) — schematic netlist excerpt (pin names and nets, part order shuffled) for the footprints in the layout excerpt that follows; sources: Cadence DE-HDL packaged netlist, KiCad conversion of 04192023_DAF0TMB3IC0_F0TG_MB_C_brd_V02_OCP.brd

C962  Q_CAP_DIFFBUS  DIFF BUS_0.22UF 6.3V 20% X6S  pkg C0201  page 63 : \1\ = P5E_CPU0_P1_TX_C_DN<1> ; \2\ = P5E_CPU0_P1_TX_DN<1>
R743  Q_RES  10K 5% CHIP  pkg 0402LF  page 76 : A = PVDD18_S5_P0 ; B = SPI_CPU0_CLK
C2176  Q_CAP  100PF 50V 5% EMPTY  pkg 0402  page 257 : A = P12V_OCP_SFF_ISENSE_MAM ; B = GND

(kicad_pcb
	(version 20260206)
	(generator "pcbnew")
	(generator_version "10.0")
	(general
		(thickness 1.6)
		(legacy_teardrops no)
	)
	(paper "A4")
	(title_block
		(title "04192023_DAF0TMB3IC0_F0TG_MB_C_brd_V02_OCP.brd")
		(comment 1 "Grand Teton / footprints 941-943 of 8354")
	)
	(layers
		(0 "F.Cu" signal "TOP")
		(4 "In1.Cu" signal "GND")
		(6 "In2.Cu" signal "IN1")
		(8 "In3.Cu" signal "GND1")
		(10 "In4.Cu" signal "IN2")
		(12 "In5.Cu" signal "GND2")
		(14 "In6.Cu" signal "IN3")
		(16 "In7.Cu" signal "GND3")
		(18 "In8.Cu" signal "VCC")
		(20 "In9.Cu" signal "VCC1")
		(22 "In10.Cu" signal "GND4")
		(24 "In11.Cu" signal "IN4")
		(26 "In12.Cu" signal "GND5")
		(28 "In13.Cu" signal "IN5")
		(30 "In14.Cu" signal "GND6")
		(32 "In15.Cu" signal "IN6")
		(34 "In16.Cu" signal "GND7")
		(2 "B.Cu" signal "BOTTOM")
		(9 "F.Adhes" user "F.Adhesive")
		(11 "B.Adhes" user "B.Adhesive")
		(13 "F.Paste" user "Package Geometry/Pastemask Top")
		(15 "B.Paste" user "Package Geometry/Pastemask Bottom")
		(5 "F.SilkS" user "Ref Des/Silkscreen Top")
		(7 "B.SilkS" user "Ref Des/Silkscreen Bottom")
		(1 "F.Mask" user "Board Geometry/Soldermask Top")
		(3 "B.Mask" user "Board Geometry/Soldermask Bottom")
		(17 "Dwgs.User" user "User.Drawings")
		(19 "Cmts.User" user "User.Comments")
		(21 "Eco1.User" user "User.Eco1")
		(23 "Eco2.User" user "User.Eco2")
		(25 "Edge.Cuts" user "Board Geometry/Outline")
		(27 "Margin" user)
		(31 "F.CrtYd" user "Package Geometry/Place Bound Top")
		(29 "B.CrtYd" user "Package Geometry/Place Bound Bottom")
		(35 "F.Fab" user "Ref Des/Assembly Top")
		(33 "B.Fab" user "Ref Des/Assembly Bottom")
	)
	(footprint ""
		(layer "F.Cu")
		(at 331.494892 -385.23926 180)
		(property "Reference" "C962"
			(at 0 0 180)
			(layer "F.SilkS")
			(hide yes)
			(effects
				(font
					(size 1.27 1.27)
				)
			)
		)
		(property "Value" ""
			(at 0 0 180)
			(layer "F.Fab")
			(effects
				(font
					(size 1.27 1.27)
				)
			)
		)
		(duplicate_pad_numbers_are_jumpers no)
		(fp_line
			(start 0.299974 0.150114)
			(end -0.299974 0.150114)
			(stroke
				(width 0.1)
				(type default)
			)
			(layer "F.Fab")
		)
		(fp_line
			(start 0.299974 -0.150114)
			(end 0.299974 0.150114)
			(stroke
				(width 0.1)
				(type default)
			)
			(layer "F.Fab")
		)
		(fp_line
			(start -0.299974 0.150114)
			(end -0.299974 -0.150114)
			(stroke
				(width 0.1)
				(type default)
			)
			(layer "F.Fab")
		)
		(fp_line
			(start -0.299974 -0.150114)
			(end 0.299974 -0.150114)
			(stroke
				(width 0.1)
				(type default)
			)
			(layer "F.Fab")
		)
		(pad "1" smd rect
			(at -0.2667 0 180)
			(size 0.3048 0.381)
			(layers "F.Cu" "F.Mask" "F.Paste")
			(net "P5E_CPU0_P1_TX_C_DN<1>")
		)
		(pad "2" smd rect
			(at 0.2667 0 180)
			(size 0.3048 0.381)
			(layers "F.Cu" "F.Mask" "F.Paste")
			(net "P5E_CPU0_P1_TX_DN<1>")
		)
	)
	(footprint ""
		(layer "F.Cu")
		(at 315.771022 -33.715706 180)
		(property "Reference" "C2176"
			(at 0 0 180)
			(layer "F.SilkS")
			(hide yes)
			(effects
				(font
					(size 1.27 1.27)
				)
			)
		)
		(property "Value" ""
			(at 0 0 180)
			(layer "F.Fab")
			(effects
				(font
					(size 1.27 1.27)
				)
			)
		)
		(duplicate_pad_numbers_are_jumpers no)
		(fp_line
			(start 0.7874 0.4064)
			(end -0.7874 0.4064)
			(stroke
				(width 0.1524)
				(type default)
			)
			(layer "F.SilkS")
		)
		(fp_line
			(start 0.7874 -0.4064)
			(end 0.7874 0.4064)
			(stroke
				(width 0.1524)
				(type default)
			)
			(layer "F.SilkS")
		)
		(fp_line
			(start -0.7874 0.4064)
			(end -0.7874 -0.4064)
			(stroke
				(width 0.1524)
				(type default)
			)
			(layer "F.SilkS")
		)
		(fp_line
			(start -0.7874 -0.4064)
			(end 0.7874 -0.4064)
			(stroke
				(width 0.1524)
				(type default)
			)
			(layer "F.SilkS")
		)
		(fp_line
			(start 0.67945 0.3048)
			(end 0.120396 0.3048)
			(stroke
				(width 0.1)
				(type default)
			)
			(layer "F.Fab")
		)
		(fp_line
			(start 0.67945 -0.3048)
			(end 0.67945 0.3048)
			(stroke
				(width 0.1)
				(type default)
			)
			(layer "F.Fab")
		)
		(fp_line
			(start 0.12065 -0.2794)
			(end 0.12065 -0.3048)
			(stroke
				(width 0.1)
				(type default)
			)
			(layer "F.Fab")
		)
		(fp_line
			(start 0.12065 -0.3048)
			(end 0.67945 -0.3048)
			(stroke
				(width 0.1)
				(type default)
			)
			(layer "F.Fab")
		)
		(fp_line
			(start 0.120396 0.3048)
			(end 0.120396 0.2794)
			(stroke
				(width 0.1)
				(type default)
			)
			(layer "F.Fab")
		)
		(fp_line
			(start 0.120396 0.2794)
			(end -0.12065 0.2794)
			(stroke
				(width 0.1)
				(type default)
			)
			(layer "F.Fab")
		)
		(fp_line
			(start -0.12065 0.3048)
			(end -0.67945 0.3048)
			(stroke
				(width 0.1)
				(type default)
			)
			(layer "F.Fab")
		)
		(fp_line
			(start -0.12065 0.2794)
			(end -0.12065 0.3048)
			(stroke
				(width 0.1)
				(type default)
			)
			(layer "F.Fab")
		)
		(fp_line
			(start -0.12065 -0.2794)
			(end 0.12065 -0.2794)
			(stroke
				(width 0.1)
				(type default)
			)
			(layer "F.Fab")
		)
		(fp_line
			(start -0.12065 -0.305054)
			(end -0.12065 -0.2794)
			(stroke
				(width 0.1)
				(type default)
			)
			(layer "F.Fab")
		)
		(fp_line
			(start -0.67945 0.3048)
			(end -0.67945 -0.305054)
			(stroke
				(width 0.1)
				(type default)
			)
			(layer "F.Fab")
		)
		(fp_line
			(start -0.67945 -0.305054)
			(end -0.12065 -0.305054)
			(stroke
				(width 0.1)
				(type default)
			)
			(layer "F.Fab")
		)
		(pad "1" smd circle
			(at -0.40005 0 180)
			(size 0 0)
			(layers "F.Cu" "F.Mask" "F.Paste")
			(net "P12V_OCP_SFF_ISENSE_MAM")
		)
		(pad "2" smd circle
			(at 0.40005 0 180)
			(size 0 0)
			(layers "F.Cu" "F.Mask" "F.Paste")
			(net "GND")
		)
	)
	(footprint ""
		(layer "F.Cu")
		(at 403.904958 -324.862952 180)
		(property "Reference" "R743"
			(at 0 0 180)
			(layer "F.SilkS")
			(hide yes)
			(effects
				(font
					(size 1.27 1.27)
				)
			)
		)
		(property "Value" ""
			(at 0 0 180)
			(layer "F.Fab")
			(effects
				(font
					(size 1.27 1.27)
				)
			)
		)
		(duplicate_pad_numbers_are_jumpers no)
		(fp_line
			(start 0.7874 0.4064)
			(end -0.7874 0.4064)
			(stroke
				(width 0.1524)
				(type default)
			)
			(layer "F.SilkS")
		)
		(fp_line
			(start 0.7874 -0.4064)
			(end 0.7874 0.4064)
			(stroke
				(width 0.1524)
				(type default)
			)
			(layer "F.SilkS")
		)
		(fp_line
			(start -0.7874 0.4064)
			(end -0.7874 -0.4064)
			(stroke
				(width 0.1524)
				(type default)
			)
			(layer "F.SilkS")
		)
		(fp_line
			(start -0.7874 -0.4064)
			(end 0.7874 -0.4064)
			(stroke
				(width 0.1524)
				(type default)
			)
			(layer "F.SilkS")
		)
		(fp_line
			(start 0.67945 0.3048)
			(end 0.120396 0.3048)
			(stroke
				(width 0.1)
				(type default)
			)
			(layer "F.Fab")
		)
		(fp_line
			(start 0.67945 -0.3048)
			(end 0.67945 0.3048)
			(stroke
				(width 0.1)
				(type default)
			)
			(layer "F.Fab")
		)
		(fp_line
			(start 0.12065 -0.2794)
			(end 0.12065 -0.3048)
			(stroke
				(width 0.1)
				(type default)
			)
			(layer "F.Fab")
		)
		(fp_line
			(start 0.12065 -0.3048)
			(end 0.67945 -0.3048)
			(stroke
				(width 0.1)
				(type default)
			)
			(layer "F.Fab")
		)
		(fp_line
			(start 0.120396 0.3048)
			(end 0.120396 0.2794)
			(stroke
				(width 0.1)
				(type default)
			)
			(layer "F.Fab")
		)
		(fp_line
			(start 0.120396 0.2794)
			(end -0.12065 0.2794)
			(stroke
				(width 0.1)
				(type default)
			)
			(layer "F.Fab")
		)
		(fp_line
			(start -0.12065 0.3048)
			(end -0.67945 0.3048)
			(stroke
				(width 0.1)
				(type default)
			)
			(layer "F.Fab")
		)
		(fp_line
			(start -0.12065 0.2794)
			(end -0.12065 0.3048)
			(stroke
				(width 0.1)
				(type default)
			)
			(layer "F.Fab")
		)
		(fp_line
			(start -0.12065 -0.2794)
			(end 0.12065 -0.2794)
			(stroke
				(width 0.1)
				(type default)
			)
			(layer "F.Fab")
		)
		(fp_line
			(start -0.12065 -0.305054)
			(end -0.12065 -0.2794)
			(stroke
				(width 0.1)
				(type default)
			)
			(layer "F.Fab")
		)
		(fp_line
			(start -0.67945 0.3048)
			(end -0.67945 -0.305054)
			(stroke
				(width 0.1)
				(type default)
			)
			(layer "F.Fab")
		)
		(fp_line
			(start -0.67945 -0.305054)
			(end -0.12065 -0.305054)
			(stroke
				(width 0.1)
				(type default)
			)
			(layer "F.Fab")
		)
		(pad "1" smd circle
			(at -0.40005 0 180)
			(size 0 0)
			(layers "F.Cu" "F.Mask" "F.Paste")
			(net "PVDD18_S5_P0")
		)
		(pad "2" smd circle
			(at 0.40005 0 180)
			(size 0 0)
			(layers "F.Cu" "F.Mask" "F.Paste")
			(net "SPI_CPU0_CLK")
		)
	)
)
